# BASEBOARD_FAB2 (Tioga Pass) — schematic netlist excerpt (pin names and nets, part order shuffled) for the footprints in the layout excerpt that follows; sources: Cadence DE-HDL packaged netlist, KiCad conversion of Wiwynn_Tioga_Pass_MB.brd

C3N13  CAP  0.22UF 16V 10% X7R  pkg 0402  page 129 : A = DMI_CPU0_PCH_RX_DN<3> ; B = DMI_CPU0_PCH_RX_C_DN<3>
R3M6  RES  0.0 5% CHIP  pkg 0402  page 218 : A = FM_PVDDQ_DEF_EN ; B = VR_PVDDQ_DEF_VREN
R7E9  RES  0.0 5% CHIP  pkg 0402  page 95 : A = FM_THROTTLE_N ; B = FM_THROTTLE_R_N

(kicad_pcb
	(version 20260206)
	(generator "pcbnew")
	(generator_version "10.0")
	(general
		(thickness 1.6)
		(legacy_teardrops no)
	)
	(paper "A4")
	(title_block
		(title "Wiwynn_Tioga_Pass_MB.brd")
		(comment 1 "Tioga Pass / footprints 4595-4597 of 4770")
	)
	(layers
		(0 "F.Cu" signal "TOP")
		(4 "In1.Cu" signal "L2GND")
		(6 "In2.Cu" signal "L3")
		(8 "In3.Cu" signal "L4GND")
		(10 "In4.Cu" signal "L5")
		(12 "In5.Cu" signal "L6GND")
		(14 "In6.Cu" signal "L7VCC")
		(16 "In7.Cu" signal "L8VCC")
		(18 "In8.Cu" signal "L9GND")
		(20 "In9.Cu" signal "L10")
		(22 "In10.Cu" signal "L11GND")
		(24 "In11.Cu" signal "L12")
		(26 "In12.Cu" signal "L13GND")
		(2 "B.Cu" signal "BOTTOM")
		(9 "F.Adhes" user "F.Adhesive")
		(11 "B.Adhes" user "B.Adhesive")
		(13 "F.Paste" user "Package Geometry/Pastemask Top")
		(15 "B.Paste" user "Package Geometry/Pastemask Bottom")
		(5 "F.SilkS" user "Ref Des/Silkscreen Top")
		(7 "B.SilkS" user "Ref Des/Silkscreen Bottom")
		(1 "F.Mask" user "Board Geometry/Soldermask Top")
		(3 "B.Mask" user "Board Geometry/Soldermask Bottom")
		(17 "Dwgs.User" user "User.Drawings")
		(19 "Cmts.User" user "User.Comments")
		(21 "Eco1.User" user "User.Eco1")
		(23 "Eco2.User" user "User.Eco2")
		(25 "Edge.Cuts" user "Board Geometry/Outline")
		(27 "Margin" user)
		(31 "F.CrtYd" user "Package Geometry/Place Bound Top")
		(29 "B.CrtYd" user "Package Geometry/Place Bound Bottom")
		(35 "F.Fab" user "Ref Des/Assembly Top")
		(33 "B.Fab" user "Ref Des/Assembly Bottom")
	)
	(footprint ""
		(layer "B.Cu")
		(at 361.188 -133.0198 180)
		(property "Reference" "R3M6"
			(at 0 0 0)
			(layer "B.SilkS")
			(hide yes)
			(effects
				(font
					(size 1.27 1.27)
				)
				(justify mirror)
			)
		)
		(property "Value" ""
			(at 0 0 0)
			(layer "B.Fab")
			(effects
				(font
					(size 1.27 1.27)
				)
				(justify mirror)
			)
		)
		(duplicate_pad_numbers_are_jumpers no)
		(fp_poly
			(pts
				(xy 0.2794 -0.1016) (xy -0.2794 -0.1016) (xy -0.2794 0.9906) (xy 0.2794 0.9906)
			)
			(stroke
				(width 0)
				(type default)
			)
			(fill no)
			(layer "B.CrtYd")
		)
		(fp_line
			(start 0.2794 0.9906)
			(end -0.2794 0.9906)
			(stroke
				(width 0.1)
				(type default)
			)
			(layer "B.Fab")
		)
		(fp_line
			(start 0.2794 -0.1016)
			(end 0.2794 0.9906)
			(stroke
				(width 0.1)
				(type default)
			)
			(layer "B.Fab")
		)
		(fp_line
			(start -0.2794 0.9906)
			(end -0.2794 -0.1016)
			(stroke
				(width 0.1)
				(type default)
			)
			(layer "B.Fab")
		)
		(fp_line
			(start -0.2794 -0.1016)
			(end 0.2794 -0.1016)
			(stroke
				(width 0.1)
				(type default)
			)
			(layer "B.Fab")
		)
		(pad "1" smd rect
			(at 0 0)
			(size 0.508 0.508)
			(layers "B.Cu" "B.Mask" "B.Paste")
			(net "FM_PVDDQ_DEF_EN")
		)
		(pad "2" smd rect
			(at 0 0.889)
			(size 0.508 0.508)
			(layers "B.Cu" "B.Mask" "B.Paste")
			(net "VR_PVDDQ_DEF_VREN")
		)
		(zone
			(layer "B.Cu")
			(hatch none 0.5)
			(connect_pads
				(clearance 0)
			)
			(min_thickness 0.25)
			(keepout
				(tracks not_allowed)
				(vias allowed)
				(pads allowed)
				(copperpour not_allowed)
				(footprints allowed)
			)
			(placement
				(enabled no)
				(sheetname "")
			)
			(fill
				(thermal_gap 0.5)
				(thermal_bridge_width 0.5)
				(island_removal_mode 0)
			)
			(polygon
				(pts
					(xy 360.934 -133.6548) (xy 361.442 -133.6548) (xy 361.442 -133.2738) (xy 360.934 -133.2738)
				)
			)
		)
		(zone
			(layer "B.Cu")
			(hatch none 0.5)
			(connect_pads
				(clearance 0)
			)
			(min_thickness 0.25)
			(keepout
				(tracks allowed)
				(vias not_allowed)
				(pads allowed)
				(copperpour not_allowed)
				(footprints allowed)
			)
			(placement
				(enabled no)
				(sheetname "")
			)
			(fill
				(thermal_gap 0.5)
				(thermal_bridge_width 0.5)
				(island_removal_mode 0)
			)
			(polygon
				(pts
					(xy 360.934 -133.2738) (xy 361.442 -133.2738) (xy 361.442 -133.6548) (xy 360.934 -133.6548)
				)
			)
		)
	)
	(footprint ""
		(layer "B.Cu")
		(at 386.709666 -45.691806 -90)
		(property "Reference" "R7E9"
			(at 0 0 90)
			(layer "B.SilkS")
			(hide yes)
			(effects
				(font
					(size 1.27 1.27)
				)
				(justify mirror)
			)
		)
		(property "Value" ""
			(at 0 0 90)
			(layer "B.Fab")
			(effects
				(font
					(size 1.27 1.27)
				)
				(justify mirror)
			)
		)
		(duplicate_pad_numbers_are_jumpers no)
		(fp_poly
			(pts
				(xy 0.2794 -0.1016) (xy -0.2794 -0.1016) (xy -0.2794 0.9906) (xy 0.2794 0.9906)
			)
			(stroke
				(width 0)
				(type default)
			)
			(fill no)
			(layer "B.CrtYd")
		)
		(fp_line
			(start -0.2794 0.9906)
			(end -0.2794 -0.1016)
			(stroke
				(width 0.1)
				(type default)
			)
			(layer "B.Fab")
		)
		(fp_line
			(start 0.2794 0.9906)
			(end -0.2794 0.9906)
			(stroke
				(width 0.1)
				(type default)
			)
			(layer "B.Fab")
		)
		(fp_line
			(start -0.2794 -0.1016)
			(end 0.2794 -0.1016)
			(stroke
				(width 0.1)
				(type default)
			)
			(layer "B.Fab")
		)
		(fp_line
			(start 0.2794 -0.1016)
			(end 0.2794 0.9906)
			(stroke
				(width 0.1)
				(type default)
			)
			(layer "B.Fab")
		)
		(pad "1" smd rect
			(at 0 0 90)
			(size 0.508 0.508)
			(layers "B.Cu" "B.Mask" "B.Paste")
			(net "FM_THROTTLE_N")
		)
		(pad "2" smd rect
			(at 0 0.889 90)
			(size 0.508 0.508)
			(layers "B.Cu" "B.Mask" "B.Paste")
			(net "FM_THROTTLE_R_N")
		)
		(zone
			(layer "B.Cu")
			(hatch none 0.5)
			(connect_pads
				(clearance 0)
			)
			(min_thickness 0.25)
			(keepout
				(tracks not_allowed)
				(vias allowed)
				(pads allowed)
				(copperpour not_allowed)
				(footprints allowed)
			)
			(placement
				(enabled no)
				(sheetname "")
			)
			(fill
				(thermal_gap 0.5)
				(thermal_bridge_width 0.5)
				(island_removal_mode 0)
			)
			(polygon
				(pts
					(xy 386.074666 -45.437806) (xy 386.074666 -45.945806) (xy 386.455666 -45.945806) (xy 386.455666 -45.437806)
				)
			)
		)
		(zone
			(layer "B.Cu")
			(hatch none 0.5)
			(connect_pads
				(clearance 0)
			)
			(min_thickness 0.25)
			(keepout
				(tracks allowed)
				(vias not_allowed)
				(pads allowed)
				(copperpour not_allowed)
				(footprints allowed)
			)
			(placement
				(enabled no)
				(sheetname "")
			)
			(fill
				(thermal_gap 0.5)
				(thermal_bridge_width 0.5)
				(island_removal_mode 0)
			)
			(polygon
				(pts
					(xy 386.455666 -45.437806) (xy 386.455666 -45.945806) (xy 386.074666 -45.945806) (xy 386.074666 -45.437806)
				)
			)
		)
	)
	(footprint ""
		(layer "B.Cu")
		(at 369.443 -109.601 -90)
		(property "Reference" "C3N13"
			(at 0 0 90)
			(layer "B.SilkS")
			(hide yes)
			(effects
				(font
					(size 1.27 1.27)
				)
				(justify mirror)
			)
		)
		(property "Value" ""
			(at 0 0 90)
			(layer "B.Fab")
			(effects
				(font
					(size 1.27 1.27)
				)
				(justify mirror)
			)
		)
		(duplicate_pad_numbers_are_jumpers no)
		(fp_poly
			(pts
				(xy -0.3048 -0.1016) (xy -0.3048 0.9906) (xy 0.3048 0.9906) (xy 0.3048 -0.1016)
			)
			(stroke
				(width 0)
				(type default)
			)
			(fill no)
			(layer "B.CrtYd")
		)
		(fp_line
			(start -0.3048 0.9906)
			(end -0.3048 -0.1016)
			(stroke
				(width 0.1)
				(type default)
			)
			(layer "B.Fab")
		)
		(fp_line
			(start 0.3048 0.9906)
			(end -0.3048 0.9906)
			(stroke
				(width 0.1)
				(type default)
			)
			(layer "B.Fab")
		)
		(fp_line
			(start -0.3048 -0.1016)
			(end 0.3048 -0.1016)
			(stroke
				(width 0.1)
				(type default)
			)
			(layer "B.Fab")
		)
		(fp_line
			(start 0.3048 -0.1016)
			(end 0.3048 0.9906)
			(stroke
				(width 0.1)
				(type default)
			)
			(layer "B.Fab")
		)
		(pad "1" smd rect
			(at 0 0 90)
			(size 0.508 0.508)
			(layers "B.Cu" "B.Mask" "B.Paste")
			(net "DMI_CPU0_PCH_RX_DN<3>")
		)
		(pad "2" smd rect
			(at 0 0.889 90)
			(size 0.508 0.508)
			(layers "B.Cu" "B.Mask" "B.Paste")
			(net "DMI_CPU0_PCH_RX_C_DN<3>")
		)
		(zone
			(layer "B.Cu")
			(hatch none 0.5)
			(connect_pads
				(clearance 0)
			)
			(min_thickness 0.25)
			(keepout
				(tracks not_allowed)
				(vias allowed)
				(pads allowed)
				(copperpour not_allowed)
				(footprints allowed)
			)
			(placement
				(enabled no)
				(sheetname "")
			)
			(fill
				(thermal_gap 0.5)
				(thermal_bridge_width 0.5)
				(island_removal_mode 0)
			)
			(polygon
				(pts
					(xy 368.808 -109.347) (xy 368.808 -109.855) (xy 369.189 -109.855) (xy 369.189 -109.347)
				)
			)
		)
		(zone
			(layer "B.Cu")
			(hatch none 0.5)
			(connect_pads
				(clearance 0)
			)
			(min_thickness 0.25)
			(keepout
				(tracks allowed)
				(vias not_allowed)
				(pads allowed)
				(copperpour not_allowed)
				(footprints allowed)
			)
			(placement
				(enabled no)
				(sheetname "")
			)
			(fill
				(thermal_gap 0.5)
				(thermal_bridge_width 0.5)
				(island_removal_mode 0)
			)
			(polygon
				(pts
					(xy 369.189 -109.347) (xy 369.189 -109.855) (xy 368.808 -109.855) (xy 368.808 -109.347)
				)
			)
		)
	)
)
